(kicad_pcb
	(version 20221018)
	(generator pcbnew)
	(general
    (thickness 1.6)
  )
	(paper "A4")
	(title_block
    (title "NUC Computer Cluster Power Breakout HW")
    (date "2023-10-18")
    (rev "1.4.3")
    (company "Antmicro Ltd.")
		(comment 9 "footprints 226-232 of 234")
	)
	(layers
    (0 "F.Cu" mixed)
    (1 "In1.Cu" power)
    (2 "In2.Cu" mixed)
    (31 "B.Cu" power)
    (32 "B.Adhes" user "B.Adhesive")
    (33 "F.Adhes" user "F.Adhesive")
    (34 "B.Paste" user)
    (35 "F.Paste" user)
    (36 "B.SilkS" user "B.Silkscreen")
    (37 "F.SilkS" user "F.Silkscreen")
    (38 "B.Mask" user)
    (39 "F.Mask" user)
    (40 "Dwgs.User" user "User.Drawings")
    (41 "Cmts.User" user "User.Comments")
    (42 "Eco1.User" user "User.Eco1")
    (43 "Eco2.User" user "User.Eco2")
    (44 "Edge.Cuts" user)
    (45 "Margin" user)
    (46 "B.CrtYd" user "B.Courtyard")
    (47 "F.CrtYd" user "F.Courtyard")
    (48 "B.Fab" user)
    (49 "F.Fab" user)
  )
	(footprint "antmicro-footprints:Vishay_PowerPAK_1212-8_Single" (layer "F.Cu")
    (at 185.6 86.2008 90)
    (descr "PowerPAK 1212-8 Single")
    (tags "Vishay PowerPAK 1212-8 Single")
    (property "Author" "Antmicro")
    (property "License" "Apache-2.0")
    (property "MPN" "SI7613DN-T1-GE3")
    (property "Manufacturer" "Vishay")
    (property "Sheetfile" "power-switch.kicad_sch")
    (property "Sheetname" "Power switch 5")
    (property "ki_description" "Power MOSFET, P Channel, 20 V, 35 A, 0.0072 ohm, PowerPAK 1212, Surface Mount")
    (property "ki_keywords" "SMT, TRANSISTOR, SEMICONDUCTOR, MOSFET, PMOS")
    (attr smd)
    (fp_text reference "QB5" (at -2.9492 0.4 180) (layer "F.SilkS")
        (effects (font (size 0.7 0.7) (thickness 0.15)) (justify left bottom))
    )
    (fp_text value "SI7613DN-T1-GE3" (at 0 2.7 90) (layer "F.Fab")
        (effects (font (size 0.7 0.7) (thickness 0.15)) (justify left bottom))
    )
    (fp_text user "Author: Antmicro" (at -8 5.9 90) (layer "F.Fab") hide
        (effects (font (size 0.7 0.7) (thickness 0.15)) (justify left bottom))
    )
    (fp_text user "${REFERENCE}" (at -8 4.7 90) (layer "F.Fab") hide
        (effects (font (size 0.7 0.7) (thickness 0.15)) (justify left bottom))
    )
    (fp_text user "License: Apache-2.0" (at -8 7.1 90) (layer "F.Fab") hide
        (effects (font (size 0.7 0.7) (thickness 0.15)) (justify left bottom))
    )
    (fp_line (start -1.651 -1.651) (end -1.651 -1.317)
      (stroke (width 0.15) (type solid)) (layer "F.SilkS"))
    (fp_line (start -1.651 -1.651) (end 1.648 -1.651)
      (stroke (width 0.15) (type solid)) (layer "F.SilkS"))
    (fp_line (start -1.635 1.3) (end -1.635 1.634)
      (stroke (width 0.15) (type solid)) (layer "F.SilkS"))
    (fp_line (start -1.635 1.634) (end 1.634 1.634)
      (stroke (width 0.15) (type solid)) (layer "F.SilkS"))
    (fp_line (start 1.634 1.3) (end 1.634 1.634)
      (stroke (width 0.15) (type solid)) (layer "F.SilkS"))
    (fp_line (start 1.648 -1.651) (end 1.648 -1.317)
      (stroke (width 0.15) (type solid)) (layer "F.SilkS"))
    (fp_circle (center -1.9 -1.4) (end -1.85 -1.4)
      (stroke (width 0.15) (type solid)) (fill solid) (layer "F.SilkS"))
    (fp_rect (start -2 -1.8) (end 2 1.798)
      (stroke (width 0.05) (type solid)) (fill none) (layer "F.CrtYd"))
    (fp_line (start -1.6425 -1.4175) (end -1.4175 -1.6425)
      (stroke (width 0.15) (type solid)) (layer "F.Fab"))
    (fp_rect (start -1.651 -1.651) (end 1.648 1.648)
      (stroke (width 0.15) (type solid)) (fill none) (layer "F.Fab"))
    (pad "1" smd rect (at -1.436 -0.99 90) (size 0.99 0.405) (layers "F.Cu" "F.Paste" "F.Mask")
      (net 11 "VCC12V0") (pinfunction "S") (pintype "passive"))
    (pad "2" smd rect (at -1.436 -0.332 90) (size 0.99 0.405) (layers "F.Cu" "F.Paste" "F.Mask")
      (net 11 "VCC12V0") (pinfunction "S") (pintype "passive"))
    (pad "3" smd rect (at -1.436 0.33 90) (size 0.99 0.405) (layers "F.Cu" "F.Paste" "F.Mask")
      (net 11 "VCC12V0") (pinfunction "S") (pintype "passive"))
    (pad "4" smd rect (at -1.436 0.988 90) (size 0.99 0.405) (layers "F.Cu" "F.Paste" "F.Mask")
      (net 103 "Net-(QB5-G)") (pinfunction "G") (pintype "passive"))
    (pad "5" smd custom (at 0.557 0 90) (size 1.725 2.235) (layers "F.Cu" "F.Paste" "F.Mask")
      (net 25 "C_MEAS_5") (pinfunction "D") (pintype "passive") (zone_connect 2)
      (options (clearance outline) (anchor rect))
      (primitives
        (gr_poly
          (pts
            (xy 0.8625 0.1275)
            (xy 0.8625 -0.1275)
            (xy 1.3725 -0.1275)
            (xy 1.3725 -0.5325)
            (xy 0.8625 -0.5325)
            (xy 0.8625 -0.7875)
            (xy 1.3725 -0.7875)
            (xy 1.3725 -1.195)
            (xy 0.6125 -1.195)
            (xy 0.6125 1.195)
            (xy 1.3725 1.195)
            (xy 1.3725 0.7875)
            (xy 0.8625 0.7875)
            (xy 0.8625 0.5325)
            (xy 1.3725 0.5325)
            (xy 1.3725 0.1275)
          )
          (width 0) (fill yes))
      ))
  )
	(footprint "antmicro-footprints:D_SOD-323" (layer "F.Cu")
    (at 151.9 91.15 -90)
    (property "Author" "Antmicro")
    (property "License" "Apache-2.0")
    (property "MPN" "BZT52B15SV-T")
    (property "Manufacturer" "Rectron")
    (property "Sheetfile" "power-switch.kicad_sch")
    (property "Sheetname" "Power switch 3")
    (property "ki_description" "Zener Single Diode, AEC-Q101, 15 V, 500 mW, SOD-323, 2 Pins, 150 °C, Surface Mount")
    (property "ki_keywords" "SMT, DIODE, SEMICONDUCTOR, ZENER")
    (attr smd)
    (fp_text reference "D18" (at 3.7 -0.4 90) (layer "F.SilkS")
        (effects (font (size 0.7 0.7) (thickness 0.15)) (justify left bottom))
    )
    (fp_text value "BZT52B15SV-T" (at 0 1.841 -90) (layer "F.Fab")
        (effects (font (size 0.7 0.7) (thickness 0.15)) (justify left bottom))
    )
    (fp_text user "Author: Antmicro" (at -1.4 6.241 -90) (layer "F.Fab") hide
        (effects (font (size 0.7 0.7) (thickness 0.15)) (justify left bottom))
    )
    (fp_text user "${REFERENCE}" (at -1.4 5.041 -90) (layer "F.Fab") hide
        (effects (font (size 0.7 0.7) (thickness 0.15)) (justify left bottom))
    )
    (fp_text user "License: Apache-2.0" (at -1.4 3.841 -90) (layer "F.Fab") hide
        (effects (font (size 0.7 0.7) (thickness 0.15)) (justify left bottom))
    )
    (fp_line (start -0.949 -0.749) (end -0.949 -0.499)
      (stroke (width 0.15) (type solid)) (layer "F.SilkS"))
    (fp_line (start -0.949 0.501) (end -0.949 0.751)
      (stroke (width 0.15) (type solid)) (layer "F.SilkS"))
    (fp_line (start -0.6 -0.499) (end -0.6 0.499)
      (stroke (width 0.15) (type solid)) (layer "F.SilkS"))
    (fp_line (start -0.577 -0.749) (end -0.949 -0.749)
      (stroke (width 0.15) (type solid)) (layer "F.SilkS"))
    (fp_line (start -0.577 0.751) (end -0.949 0.751)
      (stroke (width 0.15) (type solid)) (layer "F.SilkS"))
    (fp_line (start 0.625 -0.736) (end 0.949 -0.736)
      (stroke (width 0.15) (type solid)) (layer "F.SilkS"))
    (fp_line (start 0.949 -0.736) (end 0.949 -0.499)
      (stroke (width 0.15) (type solid)) (layer "F.SilkS"))
    (fp_line (start 0.95 0.501) (end 0.95 0.751)
      (stroke (width 0.15) (type solid)) (layer "F.SilkS"))
    (fp_line (start 0.95 0.751) (end 0.649 0.751)
      (stroke (width 0.15) (type solid)) (layer "F.SilkS"))
    (fp_rect (start -1.6 -0.925) (end 1.6 0.925)
      (stroke (width 0.05) (type solid)) (fill none) (layer "F.CrtYd"))
    (fp_line (start -0.902 0.699) (end -0.902 -0.699)
      (stroke (width 0.15) (type solid)) (layer "F.Fab"))
    (fp_line (start -0.902 0.699) (end 0.9 0.699)
      (stroke (width 0.15) (type solid)) (layer "F.Fab"))
    (fp_line (start 0.9 -0.699) (end -0.902 -0.699)
      (stroke (width 0.15) (type solid)) (layer "F.Fab"))
    (fp_line (start 0.9 -0.699) (end 0.9 0.699)
      (stroke (width 0.15) (type solid)) (layer "F.Fab"))
    (pad "1" smd rect (at -1.125 0.001 270) (size 0.8 0.8) (layers "F.Cu" "F.Paste" "F.Mask")
      (net 11 "VCC12V0") (pinfunction "C") (pintype "passive"))
    (pad "2" smd rect (at 1.124 0.001 270) (size 0.8 0.8) (layers "F.Cu" "F.Paste" "F.Mask")
      (net 86 "Net-(D18-A)") (pinfunction "A") (pintype "passive"))
  )
	(footprint "antmicro-footprints:R_0603_1608Metric" (layer "F.Cu")
    (at 113.6 53.65)
    (descr "Resistor SMD 0603")
    (tags "resistor SMD 0603")
    (property "Author" "Antmicro")
    (property "License" "Apache-2.0")
    (property "MPN" "CR0603-FX-4701ELF")
    (property "Manufacturer" "Bourns")
    (property "Sheetfile" "d1600e-psu-breakout-board.kicad_sch")
    (property "Sheetname" "")
    (property "Tolerance" "1%")
    (property "Val" "4k7")
    (property "ki_description" "SMD Chip Resistor, 4.7 kohm, ± 1%, 100 mW, 0603 [1608 Metric], Thick Film, General Purpose")
    (property "ki_keywords" "0603, SMT, RESISTOR, PASSIVE")
    (attr smd)
    (fp_text reference "R11" (at -1.05 1.7) (layer "F.SilkS")
        (effects (font (size 0.7 0.7) (thickness 0.15)) (justify left bottom))
    )
    (fp_text value "R_4k7_0603" (at 0 1.6) (layer "F.Fab")
        (effects (font (size 0.7 0.7) (thickness 0.15)) (justify left bottom))
    )
    (fp_text user "Author: Antmicro" (at -1.25 4.9) (layer "F.Fab") hide
        (effects (font (size 0.7 0.7) (thickness 0.15)) (justify left bottom))
    )
    (fp_text user "License: Apache-2.0" (at -1.25 5.9) (layer "F.Fab") hide
        (effects (font (size 0.7 0.7) (thickness 0.15)) (justify left bottom))
    )
    (fp_text user "${REFERENCE}" (at -1.25 3.898) (layer "F.Fab") hide
        (effects (font (size 0.7 0.7) (thickness 0.15)) (justify left bottom))
    )
    (fp_line (start -0.15 -0.4) (end 0.15 -0.4)
      (stroke (width 0.15) (type solid)) (layer "F.SilkS"))
    (fp_line (start -0.15 0.4) (end 0.15 0.4)
      (stroke (width 0.15) (type solid)) (layer "F.SilkS"))
    (fp_rect (start -1.25 -0.65) (end 1.25 0.65)
      (stroke (width 0.05) (type solid)) (fill none) (layer "F.CrtYd"))
    (fp_rect (start -0.8 -0.4) (end 0.8 0.4)
      (stroke (width 0.15) (type solid)) (fill none) (layer "F.Fab"))
    (pad "1" smd roundrect (at -0.7 0) (size 0.8 1) (layers "F.Cu" "F.Paste" "F.Mask") (roundrect_rratio 0.2)
      (net 36 "Net-(D3-A)") (pintype "passive"))
    (pad "2" smd roundrect (at 0.7 0) (size 0.8 1) (layers "F.Cu" "F.Paste" "F.Mask") (roundrect_rratio 0.2)
      (net 41 "LOAD_1") (pintype "passive"))
  )
	(footprint "antmicro-footprints:R_0402_1005Metric" (layer "F.Cu")
    (at 138.45 91.75 -90)
    (descr "Resistor SMD 0402")
    (tags "resistor SMD 0402")
    (property "Author" "Antmicro")
    (property "License" "Apache-2.0")
    (property "MPN" "CR0402-FX-2R00GLF")
    (property "Manufacturer" "Bourns")
    (property "Sheetfile" "power-switch.kicad_sch")
    (property "Sheetname" "Power switch 2")
    (property "Tolerance" "1%")
    (property "Val" "2R")
    (property "ki_description" "SMD Chip Resistor")
    (property "ki_keywords" "0402, SMT, RESISTOR, PASSIVE")
    (attr smd)
    (fp_text reference "R61" (at 0.85 -0.4 90) (layer "F.SilkS")
        (effects (font (size 0.7 0.7) (thickness 0.15)) (justify right bottom))
    )
    (fp_text value "R_2R_0402" (at -1.011843 1.772047 90) (layer "F.Fab")
        (effects (font (size 0.7 0.7) (thickness 0.15)) (justify right bottom))
    )
    (fp_text user "${REFERENCE}" (at -0.95 3.168 90) (layer "F.Fab") hide
        (effects (font (size 0.7 0.7) (thickness 0.15)) (justify right bottom))
    )
    (fp_text user "License: Apache-2.0" (at -0.95 5.169 90) (layer "F.Fab") hide
        (effects (font (size 0.7 0.7) (thickness 0.15)) (justify right bottom))
    )
    (fp_text user "Author: Antmicro" (at -0.95 4.169 90) (layer "F.Fab") hide
        (effects (font (size 0.7 0.7) (thickness 0.15)) (justify right bottom))
    )
    (fp_rect (start -0.925 -0.47) (end 0.925 0.47)
      (stroke (width 0.05) (type default)) (fill none) (layer "F.CrtYd"))
    (fp_rect (start -0.5 -0.25) (end 0.5 0.25)
      (stroke (width 0.15) (type solid)) (fill none) (layer "F.Fab"))
    (pad "1" smd roundrect (at -0.48 0 270) (size 0.59 0.64) (layers "F.Cu" "F.Paste" "F.Mask") (roundrect_rratio 0.25)
      (net 100 "Net-(QB2-G)") (pintype "passive"))
    (pad "2" smd roundrect (at 0.48 0 270) (size 0.59 0.64) (layers "F.Cu" "F.Paste" "F.Mask") (roundrect_rratio 0.25)
      (net 84 "Net-(D16-A)") (pintype "passive"))
  )
	(footprint "antmicro-footprints:R_0603_1608Metric" (layer "F.Cu")
    (at 96.9 99)
    (descr "Resistor SMD 0603")
    (tags "resistor SMD 0603")
    (property "Author" "Antmicro")
    (property "License" "Apache-2.0")
    (property "MPN" "CR0603-FX-1001ELF")
    (property "Manufacturer" "Bourns")
    (property "Sheetfile" "d1600e-psu-breakout-board.kicad_sch")
    (property "Sheetname" "")
    (property "Tolerance" "1%")
    (property "Val" "1k")
    (property "ki_description" "SMD Chip Resistor, 1 kohm, ± 1%, 100 mW, 0603 [1608 Metric], Thick Film, General Purpose")
    (property "ki_keywords" "0603, SMT, RESISTOR, PASSIVE")
    (attr smd)
    (fp_text reference "R55" (at -1.05 -0.6) (layer "F.SilkS")
        (effects (font (size 0.7 0.7) (thickness 0.15)) (justify left bottom))
    )
    (fp_text value "R_1k_0603" (at 0 1.6) (layer "F.Fab")
        (effects (font (size 0.7 0.7) (thickness 0.15)) (justify left bottom))
    )
    (fp_text user "Author: Antmicro" (at -1.25 4.9) (layer "F.Fab") hide
        (effects (font (size 0.7 0.7) (thickness 0.15)) (justify left bottom))
    )
    (fp_text user "License: Apache-2.0" (at -1.25 5.9) (layer "F.Fab") hide
        (effects (font (size 0.7 0.7) (thickness 0.15)) (justify left bottom))
    )
    (fp_text user "${REFERENCE}" (at -1.25 3.898) (layer "F.Fab") hide
        (effects (font (size 0.7 0.7) (thickness 0.15)) (justify left bottom))
    )
    (fp_line (start -0.15 -0.4) (end 0.15 -0.4)
      (stroke (width 0.15) (type solid)) (layer "F.SilkS"))
    (fp_line (start -0.15 0.4) (end 0.15 0.4)
      (stroke (width 0.15) (type solid)) (layer "F.SilkS"))
    (fp_rect (start -1.25 -0.65) (end 1.25 0.65)
      (stroke (width 0.05) (type solid)) (fill none) (layer "F.CrtYd"))
    (fp_rect (start -0.8 -0.4) (end 0.8 0.4)
      (stroke (width 0.15) (type solid)) (fill none) (layer "F.Fab"))
    (pad "1" smd roundrect (at -0.7 0) (size 0.8 1) (layers "F.Cu" "F.Paste" "F.Mask") (roundrect_rratio 0.2)
      (net 79 "Net-(D10-A)") (pintype "passive"))
    (pad "2" smd roundrect (at 0.7 0) (size 0.8 1) (layers "F.Cu" "F.Paste" "F.Mask") (roundrect_rratio 0.2)
      (net 2 "VCC5V0") (pintype "passive"))
  )
	(footprint "antmicro-footprints:Vishay_PowerPAK_1212-8_Single" (layer "F.Cu")
    (at 181.79 87.35 90)
    (descr "PowerPAK 1212-8 Single")
    (tags "Vishay PowerPAK 1212-8 Single")
    (property "Author" "Antmicro")
    (property "License" "Apache-2.0")
    (property "MPN" "SI7613DN-T1-GE3")
    (property "Manufacturer" "Vishay")
    (property "Sheetfile" "power-switch.kicad_sch")
    (property "Sheetname" "Power switch 5")
    (property "ki_description" "Power MOSFET, P Channel, 20 V, 35 A, 0.0072 ohm, PowerPAK 1212, Surface Mount")
    (property "ki_keywords" "SMT, TRANSISTOR, SEMICONDUCTOR, MOSFET, PMOS")
    (attr smd)
    (fp_text reference "QA5" (at 3.5 1.61 180) (layer "F.SilkS")
        (effects (font (size 0.7 0.7) (thickness 0.15)) (justify left bottom))
    )
    (fp_text value "SI7613DN-T1-GE3" (at 0 2.7 90) (layer "F.Fab")
        (effects (font (size 0.7 0.7) (thickness 0.15)) (justify left bottom))
    )
    (fp_text user "${REFERENCE}" (at -8 4.7 90) (layer "F.Fab") hide
        (effects (font (size 0.7 0.7) (thickness 0.15)) (justify left bottom))
    )
    (fp_text user "Author: Antmicro" (at -8 5.9 90) (layer "F.Fab") hide
        (effects (font (size 0.7 0.7) (thickness 0.15)) (justify left bottom))
    )
    (fp_text user "License: Apache-2.0" (at -8 7.1 90) (layer "F.Fab") hide
        (effects (font (size 0.7 0.7) (thickness 0.15)) (justify left bottom))
    )
    (fp_line (start -1.651 -1.651) (end -1.651 -1.317)
      (stroke (width 0.15) (type solid)) (layer "F.SilkS"))
    (fp_line (start -1.651 -1.651) (end 1.648 -1.651)
      (stroke (width 0.15) (type solid)) (layer "F.SilkS"))
    (fp_line (start -1.635 1.3) (end -1.635 1.634)
      (stroke (width 0.15) (type solid)) (layer "F.SilkS"))
    (fp_line (start -1.635 1.634) (end 1.634 1.634)
      (stroke (width 0.15) (type solid)) (layer "F.SilkS"))
    (fp_line (start 1.634 1.3) (end 1.634 1.634)
      (stroke (width 0.15) (type solid)) (layer "F.SilkS"))
    (fp_line (start 1.648 -1.651) (end 1.648 -1.317)
      (stroke (width 0.15) (type solid)) (layer "F.SilkS"))
    (fp_circle (center -1.9 -1.4) (end -1.85 -1.4)
      (stroke (width 0.15) (type solid)) (fill solid) (layer "F.SilkS"))
    (fp_rect (start -2 -1.8) (end 2 1.798)
      (stroke (width 0.05) (type solid)) (fill none) (layer "F.CrtYd"))
    (fp_line (start -1.6425 -1.4175) (end -1.4175 -1.6425)
      (stroke (width 0.15) (type solid)) (layer "F.Fab"))
    (fp_rect (start -1.651 -1.651) (end 1.648 1.648)
      (stroke (width 0.15) (type solid)) (fill none) (layer "F.Fab"))
    (pad "1" smd rect (at -1.436 -0.99 90) (size 0.99 0.405) (layers "F.Cu" "F.Paste" "F.Mask")
      (net 11 "VCC12V0") (pinfunction "S") (pintype "passive"))
    (pad "2" smd rect (at -1.436 -0.332 90) (size 0.99 0.405) (layers "F.Cu" "F.Paste" "F.Mask")
      (net 11 "VCC12V0") (pinfunction "S") (pintype "passive"))
    (pad "3" smd rect (at -1.436 0.33 90) (size 0.99 0.405) (layers "F.Cu" "F.Paste" "F.Mask")
      (net 11 "VCC12V0") (pinfunction "S") (pintype "passive"))
    (pad "4" smd rect (at -1.436 0.988 90) (size 0.99 0.405) (layers "F.Cu" "F.Paste" "F.Mask")
      (net 97 "Net-(QA5-G)") (pinfunction "G") (pintype "passive"))
    (pad "5" smd custom (at 0.557 0 90) (size 1.725 2.235) (layers "F.Cu" "F.Paste" "F.Mask")
      (net 25 "C_MEAS_5") (pinfunction "D") (pintype "passive") (zone_connect 2)
      (options (clearance outline) (anchor rect))
      (primitives
        (gr_poly
          (pts
            (xy 0.8625 0.1275)
            (xy 0.8625 -0.1275)
            (xy 1.3725 -0.1275)
            (xy 1.3725 -0.5325)
            (xy 0.8625 -0.5325)
            (xy 0.8625 -0.7875)
            (xy 1.3725 -0.7875)
            (xy 1.3725 -1.195)
            (xy 0.6125 -1.195)
            (xy 0.6125 1.195)
            (xy 1.3725 1.195)
            (xy 1.3725 0.7875)
            (xy 0.8625 0.7875)
            (xy 0.8625 0.5325)
            (xy 1.3725 0.5325)
            (xy 1.3725 0.1275)
          )
          (width 0) (fill yes))
      ))
  )
	(footprint "antmicro-footprints:R_0402_1005Metric" (layer "F.Cu")
    (at 186.55 90.1 -90)
    (descr "Resistor SMD 0402")
    (tags "resistor SMD 0402")
    (property "Author" "Antmicro")
    (property "License" "Apache-2.0")
    (property "MPN" "CR0402-FX-2R00GLF")
    (property "Manufacturer" "Bourns")
    (property "Sheetfile" "power-switch.kicad_sch")
    (property "Sheetname" "Power switch 5")
    (property "Tolerance" "1%")
    (property "Val" "2R")
    (property "ki_description" "SMD Chip Resistor")
    (property "ki_keywords" "0402, SMT, RESISTOR, PASSIVE")
    (attr smd)
    (fp_text reference "R68" (at 1.15 -1.35 -90) (layer "F.SilkS")
        (effects (font (size 0.7 0.7) (thickness 0.15)) (justify left bottom))
    )
    (fp_text value "R_2R_0402" (at -1.011843 1.772047 -90) (layer "F.Fab")
        (effects (font (size 0.7 0.7) (thickness 0.15)) (justify left bottom))
    )
    (fp_text user "${REFERENCE}" (at -0.95 3.168 -90) (layer "F.Fab") hide
        (effects (font (size 0.7 0.7) (thickness 0.15)) (justify left bottom))
    )
    (fp_text user "Author: Antmicro" (at -0.95 4.169 -90) (layer "F.Fab") hide
        (effects (font (size 0.7 0.7) (thickness 0.15)) (justify left bottom))
    )
    (fp_text user "License: Apache-2.0" (at -0.95 5.169 -90) (layer "F.Fab") hide
        (effects (font (size 0.7 0.7) (thickness 0.15)) (justify left bottom))
    )
    (fp_rect (start -0.925 -0.47) (end 0.925 0.47)
      (stroke (width 0.05) (type default)) (fill none) (layer "F.CrtYd"))
    (fp_rect (start -0.5 -0.25) (end 0.5 0.25)
      (stroke (width 0.15) (type solid)) (fill none) (layer "F.Fab"))
    (pad "1" smd roundrect (at -0.48 0 270) (size 0.59 0.64) (layers "F.Cu" "F.Paste" "F.Mask") (roundrect_rratio 0.25)
      (net 103 "Net-(QB5-G)") (pintype "passive"))
    (pad "2" smd roundrect (at 0.48 0 270) (size 0.59 0.64) (layers "F.Cu" "F.Paste" "F.Mask") (roundrect_rratio 0.25)
      (net 87 "Net-(D19-A)") (pintype "passive"))
  )
)
